(kicad_pcb
	(version 20240108)
	(generator "pcbnew")
	(generator_version "8.0")
	(general
		(thickness 1.62)
		(legacy_teardrops no)
	)
	(paper "A4")
	(title_block
		(title "Jetson Orin Baseboard")
		(date "2025-03-12")
		(rev "1.3.4")
		(company "Antmicro Ltd")
		(comment 1 "www.antmicro.com")
		(comment 9 "footprints 428-432 of 677")
	)
	(layers
		(0 "F.Cu" signal)
		(1 "In1.Cu" signal)
		(2 "In2.Cu" signal)
		(3 "In3.Cu" signal)
		(4 "In4.Cu" jumper)
		(5 "In5.Cu" signal)
		(6 "In6.Cu" signal)
		(31 "B.Cu" signal)
		(32 "B.Adhes" user "B.Adhesive")
		(33 "F.Adhes" user "F.Adhesive")
		(34 "B.Paste" user)
		(35 "F.Paste" user)
		(36 "B.SilkS" user "B.Silkscreen")
		(37 "F.SilkS" user "F.Silkscreen")
		(38 "B.Mask" user)
		(39 "F.Mask" user)
		(40 "Dwgs.User" user "User.Drawings")
		(41 "Cmts.User" user "User.Comments")
		(42 "Eco1.User" user "User.Eco1")
		(43 "Eco2.User" user "User.Eco2")
		(44 "Edge.Cuts" user)
		(45 "Margin" user)
		(46 "B.CrtYd" user "B.Courtyard")
		(47 "F.CrtYd" user "F.Courtyard")
		(48 "B.Fab" user)
		(49 "F.Fab" user)
	)
	(footprint "antmicro-footprints:C_0402_1005Metric"
		(layer "B.Cu")
		(at 93.15 85.85 -90)
		(descr "Capacitor SMD 0402")
		(tags "capacitor SMD 0402")
		(property "Reference" "C91"
			(at -1.09 0.61 90)
			(layer "B.SilkS")
			(effects
				(font
					(size 0.7 0.7)
					(thickness 0.15)
				)
				(justify left bottom mirror)
			)
		)
		(property "Value" "C_100n_0402"
			(at 0 -1.4 90)
			(layer "B.Fab")
			(effects
				(font
					(size 0.7 0.7)
					(thickness 0.15)
				)
				(justify left bottom mirror)
			)
		)
		(property "Footprint" "antmicro-footprints:C_0402_1005Metric"
			(at 0 0 -90)
			(layer "F.Fab")
			(hide yes)
			(effects
				(font
					(size 1.27 1.27)
					(thickness 0.15)
				)
			)
		)
		(property "Datasheet" "https://www.murata.com/products/productdetail?partno=GRM155R61H104KE14%23"
			(at 0 0 -90)
			(layer "F.Fab")
			(hide yes)
			(effects
				(font
					(size 1.27 1.27)
					(thickness 0.15)
				)
			)
		)
		(property "Author" "Antmicro"
			(at 7.3 179 0)
			(layer "B.Fab")
			(hide yes)
			(effects
				(font
					(size 1 1)
					(thickness 0.15)
				)
				(justify mirror)
			)
		)
		(property "Dielectric" "X5R"
			(at 7.3 179 0)
			(layer "B.Fab")
			(hide yes)
			(effects
				(font
					(size 1 1)
					(thickness 0.15)
				)
				(justify mirror)
			)
		)
		(property "License" "Apache-2.0"
			(at 7.3 179 0)
			(layer "B.Fab")
			(hide yes)
			(effects
				(font
					(size 1 1)
					(thickness 0.15)
				)
				(justify mirror)
			)
		)
		(property "MPN" "GRM155R61H104KE14D"
			(at 7.3 179 0)
			(layer "B.Fab")
			(hide yes)
			(effects
				(font
					(size 1 1)
					(thickness 0.15)
				)
				(justify mirror)
			)
		)
		(property "Manufacturer" "Murata"
			(at 7.3 179 0)
			(layer "B.Fab")
			(hide yes)
			(effects
				(font
					(size 1 1)
					(thickness 0.15)
				)
				(justify mirror)
			)
		)
		(property "Val" "100n"
			(at 7.3 179 0)
			(layer "B.Fab")
			(hide yes)
			(effects
				(font
					(size 1 1)
					(thickness 0.15)
				)
				(justify mirror)
			)
		)
		(property "Voltage" "50V"
			(at 7.3 179 0)
			(layer "B.Fab")
			(hide yes)
			(effects
				(font
					(size 1 1)
					(thickness 0.15)
				)
				(justify mirror)
			)
		)
		(sheetname "CSI")
		(sheetfile "csi.kicad_sch")
		(attr smd)
		(fp_rect
			(start -0.925 0.47)
			(end 0.925 -0.47)
			(stroke
				(width 0.05)
				(type default)
			)
			(fill none)
			(layer "B.CrtYd")
		)
		(fp_line
			(start -0.494 0.25)
			(end -0.494 -0.248)
			(stroke
				(width 0.15)
				(type solid)
			)
			(layer "B.Fab")
		)
		(fp_line
			(start 0.504 0.25)
			(end -0.494 0.25)
			(stroke
				(width 0.15)
				(type solid)
			)
			(layer "B.Fab")
		)
		(fp_line
			(start -0.494 -0.248)
			(end 0.504 -0.248)
			(stroke
				(width 0.15)
				(type solid)
			)
			(layer "B.Fab")
		)
		(fp_line
			(start 0.504 -0.248)
			(end 0.504 0.25)
			(stroke
				(width 0.15)
				(type solid)
			)
			(layer "B.Fab")
		)
		(fp_text user "Author: Antmicro"
			(at -0.932 -4.17 90)
			(layer "B.Fab")
			(hide yes)
			(effects
				(font
					(size 0.7 0.7)
					(thickness 0.15)
				)
				(justify left bottom mirror)
			)
		)
		(fp_text user "${REFERENCE}"
			(at -0.932 -3.168 90)
			(layer "B.Fab")
			(hide yes)
			(effects
				(font
					(size 0.7 0.7)
					(thickness 0.15)
				)
				(justify left bottom mirror)
			)
		)
		(fp_text user "License: Apache-2.0"
			(at -0.932 -5.17 90)
			(layer "B.Fab")
			(hide yes)
			(effects
				(font
					(size 0.7 0.7)
					(thickness 0.15)
				)
				(justify left bottom mirror)
			)
		)
		(pad "1" smd roundrect
			(at -0.48 0 270)
			(size 0.59 0.64)
			(layers "B.Cu" "B.Paste" "B.Mask")
			(roundrect_rratio 0.25)
			(net 87 "+3V3")
			(pintype "passive")
		)
		(pad "2" smd roundrect
			(at 0.48 0 270)
			(size 0.59 0.64)
			(layers "B.Cu" "B.Paste" "B.Mask")
			(roundrect_rratio 0.25)
			(net 1 "GND")
			(pintype "passive")
		)
	)
	(footprint "antmicro-footprints:R_0402_1005Metric"
		(layer "B.Cu")
		(at 91.71 102.99 -135)
		(descr "Resistor SMD 0402")
		(tags "resistor SMD 0402")
		(property "Reference" "R221"
			(at -2.884996 -1.343503 45)
			(layer "B.SilkS")
			(effects
				(font
					(size 0.7 0.7)
					(thickness 0.15)
				)
				(justify left bottom mirror)
			)
		)
		(property "Value" "R_499R_0402"
			(at -1.011843 -1.772046 45)
			(layer "B.Fab")
			(effects
				(font
					(size 0.7 0.7)
					(thickness 0.15)
				)
				(justify left bottom mirror)
			)
		)
		(property "Footprint" "antmicro-footprints:R_0402_1005Metric"
			(at 0 0 -135)
			(layer "F.Fab")
			(hide yes)
			(effects
				(font
					(size 1.27 1.27)
					(thickness 0.15)
				)
			)
		)
		(property "Datasheet" "https://www.mouser.com/datasheet/2/54/cr-1858361.pdf"
			(at 0 0 -135)
			(layer "F.Fab")
			(hide yes)
			(effects
				(font
					(size 1.27 1.27)
					(thickness 0.15)
				)
			)
		)
		(property "Author" "Antmicro"
			(at 83.733836 240.66369 0)
			(layer "B.Fab")
			(hide yes)
			(effects
				(font
					(size 1 1)
					(thickness 0.15)
				)
				(justify mirror)
			)
		)
		(property "License" "Apache-2.0"
			(at 83.733836 240.66369 0)
			(layer "B.Fab")
			(hide yes)
			(effects
				(font
					(size 1 1)
					(thickness 0.15)
				)
				(justify mirror)
			)
		)
		(property "MPN" "CR0402-FX-4990GLF"
			(at 83.733836 240.66369 0)
			(layer "B.Fab")
			(hide yes)
			(effects
				(font
					(size 1 1)
					(thickness 0.15)
				)
				(justify mirror)
			)
		)
		(property "Manufacturer" "Bourns"
			(at 83.733836 240.66369 0)
			(layer "B.Fab")
			(hide yes)
			(effects
				(font
					(size 1 1)
					(thickness 0.15)
				)
				(justify mirror)
			)
		)
		(property "Tolerance" "1%"
			(at 83.733836 240.66369 0)
			(layer "B.Fab")
			(hide yes)
			(effects
				(font
					(size 1 1)
					(thickness 0.15)
				)
				(justify mirror)
			)
		)
		(property "Val" "499R"
			(at 83.733836 240.66369 0)
			(layer "B.Fab")
			(hide yes)
			(effects
				(font
					(size 1 1)
					(thickness 0.15)
				)
				(justify mirror)
			)
		)
		(sheetname "HDMI")
		(sheetfile "hdmi.kicad_sch")
		(attr smd)
		(fp_poly
			(pts
				(xy -0.925 0.47) (xy 0.925 0.47) (xy 0.925 -0.47) (xy -0.925 -0.47)
			)
			(stroke
				(width 0.05)
				(type default)
			)
			(fill none)
			(layer "B.CrtYd")
		)
		(fp_poly
			(pts
				(xy -0.5 0.25) (xy 0.5 0.25) (xy 0.5 -0.25) (xy -0.5 -0.25)
			)
			(stroke
				(width 0.15)
				(type solid)
			)
			(fill none)
			(layer "B.Fab")
		)
		(fp_text user "Author: Antmicro"
			(at -0.95 -4.169 45)
			(layer "B.Fab")
			(hide yes)
			(effects
				(font
					(size 0.7 0.7)
					(thickness 0.15)
				)
				(justify left bottom mirror)
			)
		)
		(fp_text user "License: Apache-2.0"
			(at -0.949999 -5.169 45)
			(layer "B.Fab")
			(hide yes)
			(effects
				(font
					(size 0.7 0.7)
					(thickness 0.15)
				)
				(justify left bottom mirror)
			)
		)
		(fp_text user "${REFERENCE}"
			(at -0.95 -3.168 45)
			(layer "B.Fab")
			(hide yes)
			(effects
				(font
					(size 0.7 0.7)
					(thickness 0.15)
				)
				(justify left bottom mirror)
			)
		)
		(pad "1" smd roundrect
			(at -0.48 0 225)
			(size 0.59 0.64)
			(layers "B.Cu" "B.Paste" "B.Mask")
			(roundrect_rratio 0.25)
			(net 623 "Net-(Q2-D)")
			(pintype "passive")
		)
		(pad "2" smd roundrect
			(at 0.48 0 225)
			(size 0.59 0.64)
			(layers "B.Cu" "B.Paste" "B.Mask")
			(roundrect_rratio 0.25)
			(net 489 "/HDMI/HDMI_CLK_N")
			(pintype "passive")
		)
	)
	(footprint "antmicro-footprints:R_0402_1005Metric"
		(layer "B.Cu")
		(at 54.4 99.74 90)
		(descr "Resistor SMD 0402")
		(tags "resistor SMD 0402")
		(property "Reference" "R155"
			(at -1.4 -0.5 90)
			(layer "B.SilkS")
			(effects
				(font
					(size 0.7 0.7)
					(thickness 0.15)
				)
				(justify right bottom mirror)
			)
		)
		(property "Value" "R_1k_0402"
			(at 0 -1.4 90)
			(layer "B.Fab")
			(effects
				(font
					(size 0.7 0.7)
					(thickness 0.15)
				)
				(justify right bottom mirror)
			)
		)
		(property "Footprint" "antmicro-footprints:R_0402_1005Metric"
			(at 0 0 90)
			(layer "F.Fab")
			(hide yes)
			(effects
				(font
					(size 1.27 1.27)
					(thickness 0.15)
				)
			)
		)
		(property "Datasheet" "https://www.bourns.com/docs/product-datasheets/cr.pdf"
			(at 0 0 90)
			(layer "F.Fab")
			(hide yes)
			(effects
				(font
					(size 1.27 1.27)
					(thickness 0.15)
				)
			)
		)
		(property "Author" "Antmicro"
			(at 154.14 45.34 0)
			(layer "B.Fab")
			(hide yes)
			(effects
				(font
					(size 1 1)
					(thickness 0.15)
				)
				(justify mirror)
			)
		)
		(property "License" "Apache-2.0"
			(at 154.14 45.34 0)
			(layer "B.Fab")
			(hide yes)
			(effects
				(font
					(size 1 1)
					(thickness 0.15)
				)
				(justify mirror)
			)
		)
		(property "MPN" "CR0402-FX-1001GLF"
			(at 154.14 45.34 0)
			(layer "B.Fab")
			(hide yes)
			(effects
				(font
					(size 1 1)
					(thickness 0.15)
				)
				(justify mirror)
			)
		)
		(property "Manufacturer" "Bourns"
			(at 154.14 45.34 0)
			(layer "B.Fab")
			(hide yes)
			(effects
				(font
					(size 1 1)
					(thickness 0.15)
				)
				(justify mirror)
			)
		)
		(property "Tolerance" "1%"
			(at 154.14 45.34 0)
			(layer "B.Fab")
			(hide yes)
			(effects
				(font
					(size 1 1)
					(thickness 0.15)
				)
				(justify mirror)
			)
		)
		(property "Val" "1k"
			(at 154.14 45.34 0)
			(layer "B.Fab")
			(hide yes)
			(effects
				(font
					(size 1 1)
					(thickness 0.15)
				)
				(justify mirror)
			)
		)
		(sheetname "Ethernet")
		(sheetfile "ethernet.kicad_sch")
		(attr smd)
		(fp_rect
			(start -0.925 0.47)
			(end 0.925 -0.47)
			(stroke
				(width 0.05)
				(type default)
			)
			(fill none)
			(layer "B.CrtYd")
		)
		(fp_rect
			(start -0.5 0.25)
			(end 0.5 -0.25)
			(stroke
				(width 0.15)
				(type solid)
			)
			(fill none)
			(layer "B.Fab")
		)
		(fp_text user "${REFERENCE}"
			(at -0.95 -3.168 90)
			(layer "B.Fab")
			(hide yes)
			(effects
				(font
					(size 0.7 0.7)
					(thickness 0.15)
				)
				(justify right bottom mirror)
			)
		)
		(fp_text user "License: Apache-2.0"
			(at -0.95 -5.169 90)
			(layer "B.Fab")
			(hide yes)
			(effects
				(font
					(size 0.7 0.7)
					(thickness 0.15)
				)
				(justify right bottom mirror)
			)
		)
		(fp_text user "Author: Antmicro"
			(at -0.95 -4.169 90)
			(layer "B.Fab")
			(hide yes)
			(effects
				(font
					(size 0.7 0.7)
					(thickness 0.15)
				)
				(justify right bottom mirror)
			)
		)
		(pad "1" smd roundrect
			(at -0.48 0 90)
			(size 0.59 0.64)
			(layers "B.Cu" "B.Paste" "B.Mask")
			(roundrect_rratio 0.25)
			(net 106 "GNDD")
			(pintype "passive")
		)
		(pad "2" smd roundrect
			(at 0.48 0 90)
			(size 0.59 0.64)
			(layers "B.Cu" "B.Paste" "B.Mask")
			(roundrect_rratio 0.25)
			(net 730 "Net-(R155-Pad2)")
			(pintype "passive")
		)
	)
	(footprint "antmicro-footprints:C_0402_1005Metric"
		(layer "B.Cu")
		(at 106 92.02 180)
		(descr "Capacitor SMD 0402")
		(tags "capacitor SMD 0402")
		(property "Reference" "C8"
			(at 0.8 -0.45 0)
			(layer "B.SilkS")
			(effects
				(font
					(size 0.7 0.7)
					(thickness 0.15)
				)
				(justify left bottom mirror)
			)
		)
		(property "Value" "C_100n_0402"
			(at 0 -1.4 0)
			(layer "B.Fab")
			(effects
				(font
					(size 0.7 0.7)
					(thickness 0.15)
				)
				(justify left bottom mirror)
			)
		)
		(property "Footprint" "antmicro-footprints:C_0402_1005Metric"
			(at 0 0 180)
			(layer "F.Fab")
			(hide yes)
			(effects
				(font
					(size 1.27 1.27)
					(thickness 0.15)
				)
			)
		)
		(property "Datasheet" "https://www.murata.com/products/productdetail?partno=GRM155R61H104KE14%23"
			(at 0 0 180)
			(layer "F.Fab")
			(hide yes)
			(effects
				(font
					(size 1.27 1.27)
					(thickness 0.15)
				)
			)
		)
		(property "Author" "Antmicro"
			(at 212 184.04 0)
			(layer "B.Fab")
			(hide yes)
			(effects
				(font
					(size 1 1)
					(thickness 0.15)
				)
				(justify mirror)
			)
		)
		(property "Dielectric" "X5R"
			(at 212 184.04 0)
			(layer "B.Fab")
			(hide yes)
			(effects
				(font
					(size 1 1)
					(thickness 0.15)
				)
				(justify mirror)
			)
		)
		(property "License" "Apache-2.0"
			(at 212 184.04 0)
			(layer "B.Fab")
			(hide yes)
			(effects
				(font
					(size 1 1)
					(thickness 0.15)
				)
				(justify mirror)
			)
		)
		(property "MPN" "GRM155R61H104KE14D"
			(at 212 184.04 0)
			(layer "B.Fab")
			(hide yes)
			(effects
				(font
					(size 1 1)
					(thickness 0.15)
				)
				(justify mirror)
			)
		)
		(property "Manufacturer" "Murata"
			(at 212 184.04 0)
			(layer "B.Fab")
			(hide yes)
			(effects
				(font
					(size 1 1)
					(thickness 0.15)
				)
				(justify mirror)
			)
		)
		(property "Val" "100n"
			(at 212 184.04 0)
			(layer "B.Fab")
			(hide yes)
			(effects
				(font
					(size 1 1)
					(thickness 0.15)
				)
				(justify mirror)
			)
		)
		(property "Voltage" "50V"
			(at 212 184.04 0)
			(layer "B.Fab")
			(hide yes)
			(effects
				(font
					(size 1 1)
					(thickness 0.15)
				)
				(justify mirror)
			)
		)
		(sheetname "M.2")
		(sheetfile "m-2.kicad_sch")
		(attr smd)
		(fp_rect
			(start -0.925 0.47)
			(end 0.925 -0.47)
			(stroke
				(width 0.05)
				(type default)
			)
			(fill none)
			(layer "B.CrtYd")
		)
		(fp_line
			(start 0.504 0.25)
			(end -0.494 0.25)
			(stroke
				(width 0.15)
				(type solid)
			)
			(layer "B.Fab")
		)
		(fp_line
			(start 0.504 -0.248)
			(end 0.504 0.25)
			(stroke
				(width 0.15)
				(type solid)
			)
			(layer "B.Fab")
		)
		(fp_line
			(start -0.494 0.25)
			(end -0.494 -0.248)
			(stroke
				(width 0.15)
				(type solid)
			)
			(layer "B.Fab")
		)
		(fp_line
			(start -0.494 -0.248)
			(end 0.504 -0.248)
			(stroke
				(width 0.15)
				(type solid)
			)
			(layer "B.Fab")
		)
		(fp_text user "Author: Antmicro"
			(at -0.932 -4.17 0)
			(layer "B.Fab")
			(hide yes)
			(effects
				(font
					(size 0.7 0.7)
					(thickness 0.15)
				)
				(justify left bottom mirror)
			)
		)
		(fp_text user "${REFERENCE}"
			(at -0.932 -3.168 0)
			(layer "B.Fab")
			(hide yes)
			(effects
				(font
					(size 0.7 0.7)
					(thickness 0.15)
				)
				(justify left bottom mirror)
			)
		)
		(fp_text user "License: Apache-2.0"
			(at -0.932 -5.17 0)
			(layer "B.Fab")
			(hide yes)
			(effects
				(font
					(size 0.7 0.7)
					(thickness 0.15)
				)
				(justify left bottom mirror)
			)
		)
		(pad "1" smd roundrect
			(at -0.48 0 180)
			(size 0.59 0.64)
			(layers "B.Cu" "B.Paste" "B.Mask")
			(roundrect_rratio 0.25)
			(net 635 "/M.2/3V3_M2")
			(pintype "passive")
		)
		(pad "2" smd roundrect
			(at 0.48 0 180)
			(size 0.59 0.64)
			(layers "B.Cu" "B.Paste" "B.Mask")
			(roundrect_rratio 0.25)
			(net 1 "GND")
			(pintype "passive")
		)
	)
	(footprint "antmicro-footprints:TP_SMD_0.75mm"
		(layer "B.Cu")
		(at 79.625 114.83 180)
		(property "Reference" "TP30"
			(at -0.435 3.095 90)
			(layer "B.SilkS")
			(effects
				(font
					(size 0.7 0.7)
					(thickness 0.15)
				)
				(justify left bottom mirror)
			)
		)
		(property "Value" "TP_0.75mm_SMD"
			(at 0 -1.2 0)
			(layer "B.Fab")
			(effects
				(font
					(size 0.7 0.7)
					(thickness 0.15)
				)
				(justify left bottom mirror)
			)
		)
		(property "Footprint" "antmicro-footprints:TP_SMD_0.75mm"
			(at 0 0 180)
			(layer "F.Fab")
			(hide yes)
			(effects
				(font
					(size 1.27 1.27)
					(thickness 0.15)
				)
			)
		)
		(property "Author" "Antmicro"
			(at 159.25 229.66 0)
			(layer "B.Fab")
			(hide yes)
			(effects
				(font
					(size 1 1)
					(thickness 0.15)
				)
				(justify mirror)
			)
		)
		(property "License" "Apache-2.0"
			(at 159.25 229.66 0)
			(layer "B.Fab")
			(hide yes)
			(effects
				(font
					(size 1 1)
					(thickness 0.15)
				)
				(justify mirror)
			)
		)
		(property "MPN" ""
			(at 159.25 229.66 0)
			(layer "B.Fab")
			(hide yes)
			(effects
				(font
					(size 1 1)
					(thickness 0.15)
				)
				(justify mirror)
			)
		)
		(property "Manufacturer" ""
			(at 159.25 229.66 0)
			(layer "B.Fab")
			(hide yes)
			(effects
				(font
					(size 1 1)
					(thickness 0.15)
				)
				(justify mirror)
			)
		)
		(sheetname "USB Debug, DP")
		(sheetfile "usb.kicad_sch")
		(attr exclude_from_pos_files exclude_from_bom)
		(fp_circle
			(center 0 0)
			(end 0.475 0)
			(stroke
				(width 0.05)
				(type default)
			)
			(fill none)
			(layer "B.CrtYd")
		)
		(fp_text user "Author: Antmicro"
			(at -0.4 -3.901 0)
			(layer "B.Fab")
			(hide yes)
			(effects
				(font
					(size 0.7 0.7)
					(thickness 0.15)
				)
				(justify left bottom mirror)
			)
		)
		(fp_text user "${REFERENCE}"
			(at -0.4 -2.7 0)
			(layer "B.Fab")
			(hide yes)
			(effects
				(font
					(size 0.7 0.7)
					(thickness 0.15)
				)
				(justify left bottom mirror)
			)
		)
		(fp_text user "License: Apache-2.0"
			(at -0.4 -5.101 0)
			(layer "B.Fab")
			(hide yes)
			(effects
				(font
					(size 0.7 0.7)
					(thickness 0.15)
				)
				(justify left bottom mirror)
			)
		)
		(pad "1" smd circle
			(at 0 0 180)
			(size 0.75 0.75)
			(layers "B.Cu" "B.Mask")
			(net 677 "USBC_HPD")
			(pinfunction "1")
			(pintype "passive")
		)
	)
)
